(kicad_pcb
	(version 20260206)
	(generator "pcbnew")
	(generator_version "10.0")
	(general
		(thickness 1.6)
		(legacy_teardrops no)
	)
	(paper "A4")
	(title_block
		(title "04192023_DAF0TMB3IC0_F0TG_MB_C_brd_V02_OCP.brd")
		(comment 1 "Grand Teton / footprints 7655-7661 of 8354")
	)
	(layers
		(0 "F.Cu" signal "TOP")
		(4 "In1.Cu" signal "GND")
		(6 "In2.Cu" signal "IN1")
		(8 "In3.Cu" signal "GND1")
		(10 "In4.Cu" signal "IN2")
		(12 "In5.Cu" signal "GND2")
		(14 "In6.Cu" signal "IN3")
		(16 "In7.Cu" signal "GND3")
		(18 "In8.Cu" signal "VCC")
		(20 "In9.Cu" signal "VCC1")
		(22 "In10.Cu" signal "GND4")
		(24 "In11.Cu" signal "IN4")
		(26 "In12.Cu" signal "GND5")
		(28 "In13.Cu" signal "IN5")
		(30 "In14.Cu" signal "GND6")
		(32 "In15.Cu" signal "IN6")
		(34 "In16.Cu" signal "GND7")
		(2 "B.Cu" signal "BOTTOM")
		(9 "F.Adhes" user "F.Adhesive")
		(11 "B.Adhes" user "B.Adhesive")
		(13 "F.Paste" user "Package Geometry/Pastemask Top")
		(15 "B.Paste" user "Package Geometry/Pastemask Bottom")
		(5 "F.SilkS" user "Ref Des/Silkscreen Top")
		(7 "B.SilkS" user "Ref Des/Silkscreen Bottom")
		(1 "F.Mask" user "Board Geometry/Soldermask Top")
		(3 "B.Mask" user "Board Geometry/Soldermask Bottom")
		(17 "Dwgs.User" user "User.Drawings")
		(19 "Cmts.User" user "User.Comments")
		(21 "Eco1.User" user "User.Eco1")
		(23 "Eco2.User" user "User.Eco2")
		(25 "Edge.Cuts" user "Board Geometry/Outline")
		(27 "Margin" user)
		(31 "F.CrtYd" user "Package Geometry/Place Bound Top")
		(29 "B.CrtYd" user "Package Geometry/Place Bound Bottom")
		(35 "F.Fab" user "Ref Des/Assembly Top")
		(33 "B.Fab" user "Ref Des/Assembly Bottom")
	)
	(footprint ""
		(layer "B.Cu")
		(at 338.550758 -214.880952 90)
		(property "Reference" "R436"
			(at 0 0 90)
			(layer "B.SilkS")
			(hide yes)
			(effects
				(font
					(size 1.27 1.27)
				)
				(justify mirror)
			)
		)
		(property "Value" ""
			(at 0 0 90)
			(layer "B.Fab")
			(effects
				(font
					(size 1.27 1.27)
				)
				(justify mirror)
			)
		)
		(duplicate_pad_numbers_are_jumpers no)
		(fp_line
			(start 0.7874 -0.4064)
			(end -0.7874 -0.4064)
			(stroke
				(width 0.1524)
				(type default)
			)
			(layer "B.SilkS")
		)
		(fp_line
			(start -0.7874 -0.4064)
			(end -0.7874 -0.095758)
			(stroke
				(width 0.1524)
				(type default)
			)
			(layer "B.SilkS")
		)
		(fp_line
			(start 0.7874 -0.019558)
			(end 0.7874 -0.4064)
			(stroke
				(width 0.1524)
				(type default)
			)
			(layer "B.SilkS")
		)
		(fp_line
			(start -0.377952 0.4064)
			(end 0.384048 0.4064)
			(stroke
				(width 0.1524)
				(type default)
			)
			(layer "B.SilkS")
		)
		(fp_line
			(start 0.67945 -0.305054)
			(end 0.12065 -0.305054)
			(stroke
				(width 0.1)
				(type default)
			)
			(layer "B.Fab")
		)
		(fp_line
			(start 0.12065 -0.305054)
			(end 0.12065 -0.2794)
			(stroke
				(width 0.1)
				(type default)
			)
			(layer "B.Fab")
		)
		(fp_line
			(start -0.12065 -0.3048)
			(end -0.67945 -0.3048)
			(stroke
				(width 0.1)
				(type default)
			)
			(layer "B.Fab")
		)
		(fp_line
			(start -0.67945 -0.3048)
			(end -0.67945 0.3048)
			(stroke
				(width 0.1)
				(type default)
			)
			(layer "B.Fab")
		)
		(fp_line
			(start 0.12065 -0.2794)
			(end -0.12065 -0.2794)
			(stroke
				(width 0.1)
				(type default)
			)
			(layer "B.Fab")
		)
		(fp_line
			(start -0.12065 -0.2794)
			(end -0.12065 -0.3048)
			(stroke
				(width 0.1)
				(type default)
			)
			(layer "B.Fab")
		)
		(fp_line
			(start 0.12065 0.2794)
			(end 0.12065 0.3048)
			(stroke
				(width 0.1)
				(type default)
			)
			(layer "B.Fab")
		)
		(fp_line
			(start -0.120396 0.2794)
			(end 0.12065 0.2794)
			(stroke
				(width 0.1)
				(type default)
			)
			(layer "B.Fab")
		)
		(fp_line
			(start 0.67945 0.3048)
			(end 0.67945 -0.305054)
			(stroke
				(width 0.1)
				(type default)
			)
			(layer "B.Fab")
		)
		(fp_line
			(start 0.12065 0.3048)
			(end 0.67945 0.3048)
			(stroke
				(width 0.1)
				(type default)
			)
			(layer "B.Fab")
		)
		(fp_line
			(start -0.120396 0.3048)
			(end -0.120396 0.2794)
			(stroke
				(width 0.1)
				(type default)
			)
			(layer "B.Fab")
		)
		(fp_line
			(start -0.67945 0.3048)
			(end -0.120396 0.3048)
			(stroke
				(width 0.1)
				(type default)
			)
			(layer "B.Fab")
		)
		(pad "1" smd circle
			(at 0.40005 0 270)
			(size 0 0)
			(layers "B.Cu" "B.Mask" "B.Paste")
			(net "CLK_100M_REF_OUT_DN")
		)
		(pad "2" smd circle
			(at -0.40005 0 270)
			(size 0 0)
			(layers "B.Cu" "B.Mask" "B.Paste")
			(net "CLK_100M_REF_IN_DN")
		)
	)
	(footprint ""
		(layer "B.Cu")
		(at 367.741454 -250.89231)
		(property "Reference" "C271"
			(at 0 0 0)
			(layer "B.SilkS")
			(hide yes)
			(effects
				(font
					(size 1.27 1.27)
				)
				(justify mirror)
			)
		)
		(property "Value" ""
			(at 0 0 0)
			(layer "B.Fab")
			(effects
				(font
					(size 1.27 1.27)
				)
				(justify mirror)
			)
		)
		(duplicate_pad_numbers_are_jumpers no)
		(fp_line
			(start -0.7874 -0.4064)
			(end -0.7874 0.4064)
			(stroke
				(width 0.1524)
				(type default)
			)
			(layer "B.SilkS")
		)
		(fp_line
			(start -0.7874 0.4064)
			(end 0.7874 0.4064)
			(stroke
				(width 0.1524)
				(type default)
			)
			(layer "B.SilkS")
		)
		(fp_line
			(start 0.7874 -0.4064)
			(end -0.7874 -0.4064)
			(stroke
				(width 0.1524)
				(type default)
			)
			(layer "B.SilkS")
		)
		(fp_line
			(start 0.7874 0.4064)
			(end 0.7874 -0.4064)
			(stroke
				(width 0.1524)
				(type default)
			)
			(layer "B.SilkS")
		)
		(fp_line
			(start -0.67945 -0.3048)
			(end -0.67945 0.3048)
			(stroke
				(width 0.1)
				(type default)
			)
			(layer "B.Fab")
		)
		(fp_line
			(start -0.67945 0.3048)
			(end -0.120396 0.3048)
			(stroke
				(width 0.1)
				(type default)
			)
			(layer "B.Fab")
		)
		(fp_line
			(start -0.12065 -0.3048)
			(end -0.67945 -0.3048)
			(stroke
				(width 0.1)
				(type default)
			)
			(layer "B.Fab")
		)
		(fp_line
			(start -0.12065 -0.2794)
			(end -0.12065 -0.3048)
			(stroke
				(width 0.1)
				(type default)
			)
			(layer "B.Fab")
		)
		(fp_line
			(start -0.120396 0.2794)
			(end 0.12065 0.2794)
			(stroke
				(width 0.1)
				(type default)
			)
			(layer "B.Fab")
		)
		(fp_line
			(start -0.120396 0.3048)
			(end -0.120396 0.2794)
			(stroke
				(width 0.1)
				(type default)
			)
			(layer "B.Fab")
		)
		(fp_line
			(start 0.12065 -0.305054)
			(end 0.12065 -0.2794)
			(stroke
				(width 0.1)
				(type default)
			)
			(layer "B.Fab")
		)
		(fp_line
			(start 0.12065 -0.2794)
			(end -0.12065 -0.2794)
			(stroke
				(width 0.1)
				(type default)
			)
			(layer "B.Fab")
		)
		(fp_line
			(start 0.12065 0.2794)
			(end 0.12065 0.3048)
			(stroke
				(width 0.1)
				(type default)
			)
			(layer "B.Fab")
		)
		(fp_line
			(start 0.12065 0.3048)
			(end 0.67945 0.3048)
			(stroke
				(width 0.1)
				(type default)
			)
			(layer "B.Fab")
		)
		(fp_line
			(start 0.67945 -0.305054)
			(end 0.12065 -0.305054)
			(stroke
				(width 0.1)
				(type default)
			)
			(layer "B.Fab")
		)
		(fp_line
			(start 0.67945 0.3048)
			(end 0.67945 -0.305054)
			(stroke
				(width 0.1)
				(type default)
			)
			(layer "B.Fab")
		)
		(pad "1" smd circle
			(at 0.40005 0 180)
			(size 0 0)
			(layers "B.Cu" "B.Mask" "B.Paste")
			(net "PVDDCR_CPU0_P0")
		)
		(pad "2" smd circle
			(at -0.40005 0 180)
			(size 0 0)
			(layers "B.Cu" "B.Mask" "B.Paste")
			(net "GND")
		)
	)
	(footprint ""
		(layer "B.Cu")
		(at 299.265594 -391.06856 180)
		(property "Reference" "R972"
			(at 0 0 0)
			(layer "B.SilkS")
			(hide yes)
			(effects
				(font
					(size 1.27 1.27)
				)
				(justify mirror)
			)
		)
		(property "Value" ""
			(at 0 0 0)
			(layer "B.Fab")
			(effects
				(font
					(size 1.27 1.27)
				)
				(justify mirror)
			)
		)
		(duplicate_pad_numbers_are_jumpers no)
		(fp_line
			(start 0.32512 0.175006)
			(end 0.32512 -0.175006)
			(stroke
				(width 0.1)
				(type default)
			)
			(layer "B.Fab")
		)
		(fp_line
			(start 0.32512 -0.175006)
			(end -0.32512 -0.175006)
			(stroke
				(width 0.1)
				(type default)
			)
			(layer "B.Fab")
		)
		(fp_line
			(start -0.32512 0.175006)
			(end 0.32512 0.175006)
			(stroke
				(width 0.1)
				(type default)
			)
			(layer "B.Fab")
		)
		(fp_line
			(start -0.32512 -0.175006)
			(end -0.32512 0.175006)
			(stroke
				(width 0.1)
				(type default)
			)
			(layer "B.Fab")
		)
		(pad "1" smd rect
			(at 0.2667 0)
			(size 0.3048 0.381)
			(layers "B.Cu" "B.Mask" "B.Paste")
			(net "P1V8_CPU0_RT_1D")
		)
		(pad "2" smd rect
			(at -0.2667 0 180)
			(size 0.3048 0.381)
			(layers "B.Cu" "B.Mask" "B.Paste")
			(net "RT_CPU0_P0_SCAN_MODE")
		)
	)
	(footprint ""
		(layer "B.Cu")
		(at 165.18382 -193.996564)
		(property "Reference" "R110"
			(at 0 0 0)
			(layer "B.SilkS")
			(hide yes)
			(effects
				(font
					(size 1.27 1.27)
				)
				(justify mirror)
			)
		)
		(property "Value" ""
			(at 0 0 0)
			(layer "B.Fab")
			(effects
				(font
					(size 1.27 1.27)
				)
				(justify mirror)
			)
		)
		(duplicate_pad_numbers_are_jumpers no)
		(fp_line
			(start -0.7874 -0.4064)
			(end -0.7874 0.4064)
			(stroke
				(width 0.1524)
				(type default)
			)
			(layer "B.SilkS")
		)
		(fp_line
			(start -0.7874 0.4064)
			(end 0.7874 0.4064)
			(stroke
				(width 0.1524)
				(type default)
			)
			(layer "B.SilkS")
		)
		(fp_line
			(start 0.7874 -0.4064)
			(end -0.7874 -0.4064)
			(stroke
				(width 0.1524)
				(type default)
			)
			(layer "B.SilkS")
		)
		(fp_line
			(start 0.7874 0.4064)
			(end 0.7874 -0.4064)
			(stroke
				(width 0.1524)
				(type default)
			)
			(layer "B.SilkS")
		)
		(fp_line
			(start -0.67945 -0.3048)
			(end -0.67945 0.3048)
			(stroke
				(width 0.1)
				(type default)
			)
			(layer "B.Fab")
		)
		(fp_line
			(start -0.67945 0.3048)
			(end -0.120396 0.3048)
			(stroke
				(width 0.1)
				(type default)
			)
			(layer "B.Fab")
		)
		(fp_line
			(start -0.12065 -0.3048)
			(end -0.67945 -0.3048)
			(stroke
				(width 0.1)
				(type default)
			)
			(layer "B.Fab")
		)
		(fp_line
			(start -0.12065 -0.2794)
			(end -0.12065 -0.3048)
			(stroke
				(width 0.1)
				(type default)
			)
			(layer "B.Fab")
		)
		(fp_line
			(start -0.120396 0.2794)
			(end 0.12065 0.2794)
			(stroke
				(width 0.1)
				(type default)
			)
			(layer "B.Fab")
		)
		(fp_line
			(start -0.120396 0.3048)
			(end -0.120396 0.2794)
			(stroke
				(width 0.1)
				(type default)
			)
			(layer "B.Fab")
		)
		(fp_line
			(start 0.12065 -0.305054)
			(end 0.12065 -0.2794)
			(stroke
				(width 0.1)
				(type default)
			)
			(layer "B.Fab")
		)
		(fp_line
			(start 0.12065 -0.2794)
			(end -0.12065 -0.2794)
			(stroke
				(width 0.1)
				(type default)
			)
			(layer "B.Fab")
		)
		(fp_line
			(start 0.12065 0.2794)
			(end 0.12065 0.3048)
			(stroke
				(width 0.1)
				(type default)
			)
			(layer "B.Fab")
		)
		(fp_line
			(start 0.12065 0.3048)
			(end 0.67945 0.3048)
			(stroke
				(width 0.1)
				(type default)
			)
			(layer "B.Fab")
		)
		(fp_line
			(start 0.67945 -0.305054)
			(end 0.12065 -0.305054)
			(stroke
				(width 0.1)
				(type default)
			)
			(layer "B.Fab")
		)
		(fp_line
			(start 0.67945 0.3048)
			(end 0.67945 -0.305054)
			(stroke
				(width 0.1)
				(type default)
			)
			(layer "B.Fab")
		)
		(pad "1" smd circle
			(at 0.40005 0 180)
			(size 0 0)
			(layers "B.Cu" "B.Mask" "B.Paste")
			(net "P3V3")
		)
		(pad "2" smd circle
			(at -0.40005 0 180)
			(size 0 0)
			(layers "B.Cu" "B.Mask" "B.Paste")
			(net "PWRGD_CHG_CPU1_DIMM0")
		)
	)
	(footprint ""
		(layer "B.Cu")
		(at 134.735062 -155.471876 90)
		(property "Reference" "PR213"
			(at 0 0 90)
			(layer "B.SilkS")
			(hide yes)
			(effects
				(font
					(size 1.27 1.27)
				)
				(justify mirror)
			)
		)
		(property "Value" ""
			(at 0 0 90)
			(layer "B.Fab")
			(effects
				(font
					(size 1.27 1.27)
				)
				(justify mirror)
			)
		)
		(duplicate_pad_numbers_are_jumpers no)
		(fp_line
			(start 0.7874 -0.4064)
			(end -0.7874 -0.4064)
			(stroke
				(width 0.1524)
				(type default)
			)
			(layer "B.SilkS")
		)
		(fp_line
			(start -0.7874 -0.4064)
			(end -0.7874 0.4064)
			(stroke
				(width 0.1524)
				(type default)
			)
			(layer "B.SilkS")
		)
		(fp_line
			(start 0.7874 0.4064)
			(end 0.7874 -0.4064)
			(stroke
				(width 0.1524)
				(type default)
			)
			(layer "B.SilkS")
		)
		(fp_line
			(start -0.7874 0.4064)
			(end 0.7874 0.4064)
			(stroke
				(width 0.1524)
				(type default)
			)
			(layer "B.SilkS")
		)
		(fp_line
			(start 0.67945 -0.305054)
			(end 0.12065 -0.305054)
			(stroke
				(width 0.1)
				(type default)
			)
			(layer "B.Fab")
		)
		(fp_line
			(start 0.12065 -0.305054)
			(end 0.12065 -0.2794)
			(stroke
				(width 0.1)
				(type default)
			)
			(layer "B.Fab")
		)
		(fp_line
			(start -0.12065 -0.3048)
			(end -0.67945 -0.3048)
			(stroke
				(width 0.1)
				(type default)
			)
			(layer "B.Fab")
		)
		(fp_line
			(start -0.67945 -0.3048)
			(end -0.67945 0.3048)
			(stroke
				(width 0.1)
				(type default)
			)
			(layer "B.Fab")
		)
		(fp_line
			(start 0.12065 -0.2794)
			(end -0.12065 -0.2794)
			(stroke
				(width 0.1)
				(type default)
			)
			(layer "B.Fab")
		)
		(fp_line
			(start -0.12065 -0.2794)
			(end -0.12065 -0.3048)
			(stroke
				(width 0.1)
				(type default)
			)
			(layer "B.Fab")
		)
		(fp_line
			(start 0.12065 0.2794)
			(end 0.12065 0.3048)
			(stroke
				(width 0.1)
				(type default)
			)
			(layer "B.Fab")
		)
		(fp_line
			(start -0.120396 0.2794)
			(end 0.12065 0.2794)
			(stroke
				(width 0.1)
				(type default)
			)
			(layer "B.Fab")
		)
		(fp_line
			(start 0.67945 0.3048)
			(end 0.67945 -0.305054)
			(stroke
				(width 0.1)
				(type default)
			)
			(layer "B.Fab")
		)
		(fp_line
			(start 0.12065 0.3048)
			(end 0.67945 0.3048)
			(stroke
				(width 0.1)
				(type default)
			)
			(layer "B.Fab")
		)
		(fp_line
			(start -0.120396 0.3048)
			(end -0.120396 0.2794)
			(stroke
				(width 0.1)
				(type default)
			)
			(layer "B.Fab")
		)
		(fp_line
			(start -0.67945 0.3048)
			(end -0.120396 0.3048)
			(stroke
				(width 0.1)
				(type default)
			)
			(layer "B.Fab")
		)
		(pad "1" smd circle
			(at 0.40005 0 270)
			(size 0 0)
			(layers "B.Cu" "B.Mask" "B.Paste")
			(net "PVDDCR_CPU0_P1_PVCC")
		)
		(pad "2" smd circle
			(at -0.40005 0 270)
			(size 0 0)
			(layers "B.Cu" "B.Mask" "B.Paste")
			(net "PVDDCR_SOC_P1_VCC3")
		)
	)
	(footprint ""
		(layer "B.Cu")
		(at 139.28852 -33.526222 90)
		(property "Reference" "C6043"
			(at 0 0 90)
			(layer "B.SilkS")
			(hide yes)
			(effects
				(font
					(size 1.27 1.27)
				)
				(justify mirror)
			)
		)
		(property "Value" ""
			(at 0 0 90)
			(layer "B.Fab")
			(effects
				(font
					(size 1.27 1.27)
				)
				(justify mirror)
			)
		)
		(duplicate_pad_numbers_are_jumpers no)
		(fp_line
			(start 0.7874 -0.4064)
			(end -0.7874 -0.4064)
			(stroke
				(width 0.1524)
				(type default)
			)
			(layer "B.SilkS")
		)
		(fp_line
			(start -0.7874 -0.4064)
			(end -0.7874 0.4064)
			(stroke
				(width 0.1524)
				(type default)
			)
			(layer "B.SilkS")
		)
		(fp_line
			(start 0.7874 0.4064)
			(end 0.7874 -0.4064)
			(stroke
				(width 0.1524)
				(type default)
			)
			(layer "B.SilkS")
		)
		(fp_line
			(start -0.7874 0.4064)
			(end 0.7874 0.4064)
			(stroke
				(width 0.1524)
				(type default)
			)
			(layer "B.SilkS")
		)
		(fp_line
			(start 0.67945 -0.305054)
			(end 0.12065 -0.305054)
			(stroke
				(width 0.1)
				(type default)
			)
			(layer "B.Fab")
		)
		(fp_line
			(start 0.12065 -0.305054)
			(end 0.12065 -0.2794)
			(stroke
				(width 0.1)
				(type default)
			)
			(layer "B.Fab")
		)
		(fp_line
			(start -0.12065 -0.3048)
			(end -0.67945 -0.3048)
			(stroke
				(width 0.1)
				(type default)
			)
			(layer "B.Fab")
		)
		(fp_line
			(start -0.67945 -0.3048)
			(end -0.67945 0.3048)
			(stroke
				(width 0.1)
				(type default)
			)
			(layer "B.Fab")
		)
		(fp_line
			(start 0.12065 -0.2794)
			(end -0.12065 -0.2794)
			(stroke
				(width 0.1)
				(type default)
			)
			(layer "B.Fab")
		)
		(fp_line
			(start -0.12065 -0.2794)
			(end -0.12065 -0.3048)
			(stroke
				(width 0.1)
				(type default)
			)
			(layer "B.Fab")
		)
		(fp_line
			(start 0.12065 0.2794)
			(end 0.12065 0.3048)
			(stroke
				(width 0.1)
				(type default)
			)
			(layer "B.Fab")
		)
		(fp_line
			(start -0.120396 0.2794)
			(end 0.12065 0.2794)
			(stroke
				(width 0.1)
				(type default)
			)
			(layer "B.Fab")
		)
		(fp_line
			(start 0.67945 0.3048)
			(end 0.67945 -0.305054)
			(stroke
				(width 0.1)
				(type default)
			)
			(layer "B.Fab")
		)
		(fp_line
			(start 0.12065 0.3048)
			(end 0.67945 0.3048)
			(stroke
				(width 0.1)
				(type default)
			)
			(layer "B.Fab")
		)
		(fp_line
			(start -0.120396 0.3048)
			(end -0.120396 0.2794)
			(stroke
				(width 0.1)
				(type default)
			)
			(layer "B.Fab")
		)
		(fp_line
			(start -0.67945 0.3048)
			(end -0.120396 0.3048)
			(stroke
				(width 0.1)
				(type default)
			)
			(layer "B.Fab")
		)
		(pad "1" smd circle
			(at 0.40005 0 270)
			(size 0 0)
			(layers "B.Cu" "B.Mask" "B.Paste")
			(net "P3V3_AUX_CPU0_USB_AVDD33")
		)
		(pad "2" smd circle
			(at -0.40005 0 270)
			(size 0 0)
			(layers "B.Cu" "B.Mask" "B.Paste")
			(net "GND")
		)
	)
	(footprint ""
		(layer "B.Cu")
		(at 167.377618 -416.946588 180)
		(property "Reference" "C12"
			(at 0 0 0)
			(layer "B.SilkS")
			(hide yes)
			(effects
				(font
					(size 1.27 1.27)
				)
				(justify mirror)
			)
		)
		(property "Value" ""
			(at 0 0 0)
			(layer "B.Fab")
			(effects
				(font
					(size 1.27 1.27)
				)
				(justify mirror)
			)
		)
		(duplicate_pad_numbers_are_jumpers no)
		(fp_line
			(start 0.7874 0.4064)
			(end 0.7874 -0.4064)
			(stroke
				(width 0.1524)
				(type default)
			)
			(layer "B.SilkS")
		)
		(fp_line
			(start 0.7874 -0.4064)
			(end -0.7874 -0.4064)
			(stroke
				(width 0.1524)
				(type default)
			)
			(layer "B.SilkS")
		)
		(fp_line
			(start -0.7874 0.4064)
			(end 0.7874 0.4064)
			(stroke
				(width 0.1524)
				(type default)
			)
			(layer "B.SilkS")
		)
		(fp_line
			(start -0.7874 -0.4064)
			(end -0.7874 0.4064)
			(stroke
				(width 0.1524)
				(type default)
			)
			(layer "B.SilkS")
		)
		(fp_line
			(start 0.67945 0.3048)
			(end 0.67945 -0.305054)
			(stroke
				(width 0.1)
				(type default)
			)
			(layer "B.Fab")
		)
		(fp_line
			(start 0.67945 -0.305054)
			(end 0.12065 -0.305054)
			(stroke
				(width 0.1)
				(type default)
			)
			(layer "B.Fab")
		)
		(fp_line
			(start 0.12065 0.3048)
			(end 0.67945 0.3048)
			(stroke
				(width 0.1)
				(type default)
			)
			(layer "B.Fab")
		)
		(fp_line
			(start 0.12065 0.2794)
			(end 0.12065 0.3048)
			(stroke
				(width 0.1)
				(type default)
			)
			(layer "B.Fab")
		)
		(fp_line
			(start 0.12065 -0.2794)
			(end -0.12065 -0.2794)
			(stroke
				(width 0.1)
				(type default)
			)
			(layer "B.Fab")
		)
		(fp_line
			(start 0.12065 -0.305054)
			(end 0.12065 -0.2794)
			(stroke
				(width 0.1)
				(type default)
			)
			(layer "B.Fab")
		)
		(fp_line
			(start -0.120396 0.3048)
			(end -0.120396 0.2794)
			(stroke
				(width 0.1)
				(type default)
			)
			(layer "B.Fab")
		)
		(fp_line
			(start -0.120396 0.2794)
			(end 0.12065 0.2794)
			(stroke
				(width 0.1)
				(type default)
			)
			(layer "B.Fab")
		)
		(fp_line
			(start -0.12065 -0.2794)
			(end -0.12065 -0.3048)
			(stroke
				(width 0.1)
				(type default)
			)
			(layer "B.Fab")
		)
		(fp_line
			(start -0.12065 -0.3048)
			(end -0.67945 -0.3048)
			(stroke
				(width 0.1)
				(type default)
			)
			(layer "B.Fab")
		)
		(fp_line
			(start -0.67945 0.3048)
			(end -0.120396 0.3048)
			(stroke
				(width 0.1)
				(type default)
			)
			(layer "B.Fab")
		)
		(fp_line
			(start -0.67945 -0.3048)
			(end -0.67945 0.3048)
			(stroke
				(width 0.1)
				(type default)
			)
			(layer "B.Fab")
		)
		(pad "1" smd circle
			(at 0.40005 0)
			(size 0 0)
			(layers "B.Cu" "B.Mask" "B.Paste")
			(net "GPU_3V3IO_RSVD0_FFU_ISO")
		)
		(pad "2" smd circle
			(at -0.40005 0)
			(size 0 0)
			(layers "B.Cu" "B.Mask" "B.Paste")
			(net "GND")
		)
	)
)
